# S9S_MB_2U (Grand Teton) — schematic netlist excerpt (pin names and nets, part order shuffled) for the footprints in the layout excerpt that follows; sources: Cadence DE-HDL packaged netlist, KiCad conversion of 03242023_DA0F0TMBIJ0_F0T_Motherboard_J_brd_V01_OCP.brd

C395  Q_CAP  47UF 4V 20% X6S  pkg C0805  page 75 : A = PVNN_MAIN_CPU0 ; B = GND
PR2510  Q_RES  1 1% EMPTY  pkg 0402LF  page 304 : A = P12V_HSC_ADC_P ; B = P12V_HSC_SENSE2_R1_P
C1243  Q_CAP  47UF 6.3V 20% X6S  pkg C0805  page 189 : A = P3V3_AUX ; B = GND

(kicad_pcb
	(version 20260206)
	(generator "pcbnew")
	(generator_version "10.0")
	(general
		(thickness 1.6)
		(legacy_teardrops no)
	)
	(paper "A4")
	(title_block
		(title "03242023_DA0F0TMBIJ0_F0T_Motherboard_J_brd_V01_OCP.brd")
		(comment 1 "Grand Teton / footprints 5147-5149 of 6105")
	)
	(layers
		(0 "F.Cu" signal "TOP")
		(4 "In1.Cu" signal "GND")
		(6 "In2.Cu" signal "IN1")
		(8 "In3.Cu" signal "GND1")
		(10 "In4.Cu" signal "IN2")
		(12 "In5.Cu" signal "GND2")
		(14 "In6.Cu" signal "IN3")
		(16 "In7.Cu" signal "GND3")
		(18 "In8.Cu" signal "VCC")
		(20 "In9.Cu" signal "VCC1")
		(22 "In10.Cu" signal "GND4")
		(24 "In11.Cu" signal "IN4")
		(26 "In12.Cu" signal "GND5")
		(28 "In13.Cu" signal "IN5")
		(30 "In14.Cu" signal "GND6")
		(32 "In15.Cu" signal "IN6")
		(34 "In16.Cu" signal "GND7")
		(2 "B.Cu" signal "BOTTOM")
		(9 "F.Adhes" user "F.Adhesive")
		(11 "B.Adhes" user "B.Adhesive")
		(13 "F.Paste" user "Package Geometry/Pastemask Top")
		(15 "B.Paste" user "Package Geometry/Pastemask Bottom")
		(5 "F.SilkS" user "Ref Des/Silkscreen Top")
		(7 "B.SilkS" user "Ref Des/Silkscreen Bottom")
		(1 "F.Mask" user "Board Geometry/Soldermask Top")
		(3 "B.Mask" user "Board Geometry/Soldermask Bottom")
		(17 "Dwgs.User" user "User.Drawings")
		(19 "Cmts.User" user "User.Comments")
		(21 "Eco1.User" user "User.Eco1")
		(23 "Eco2.User" user "User.Eco2")
		(25 "Edge.Cuts" user "Board Geometry/Outline")
		(27 "Margin" user)
		(31 "F.CrtYd" user "Package Geometry/Place Bound Top")
		(29 "B.CrtYd" user "Package Geometry/Place Bound Bottom")
		(35 "F.Fab" user "Ref Des/Assembly Top")
		(33 "B.Fab" user "Ref Des/Assembly Bottom")
	)
	(footprint ""
		(layer "B.Cu")
		(at 298.47413 -403.031452 90)
		(property "Reference" "PR2510"
			(at 0 0 90)
			(layer "B.SilkS")
			(hide yes)
			(effects
				(font
					(size 1.27 1.27)
				)
				(justify mirror)
			)
		)
		(property "Value" ""
			(at 0 0 90)
			(layer "B.Fab")
			(effects
				(font
					(size 1.27 1.27)
				)
				(justify mirror)
			)
		)
		(duplicate_pad_numbers_are_jumpers no)
		(fp_line
			(start 0.7874 -0.4064)
			(end -0.7874 -0.4064)
			(stroke
				(width 0.1524)
				(type default)
			)
			(layer "B.SilkS")
		)
		(fp_line
			(start -0.7874 -0.4064)
			(end -0.7874 0.4064)
			(stroke
				(width 0.1524)
				(type default)
			)
			(layer "B.SilkS")
		)
		(fp_line
			(start 0.7874 0.4064)
			(end 0.7874 -0.4064)
			(stroke
				(width 0.1524)
				(type default)
			)
			(layer "B.SilkS")
		)
		(fp_line
			(start -0.7874 0.4064)
			(end 0.7874 0.4064)
			(stroke
				(width 0.1524)
				(type default)
			)
			(layer "B.SilkS")
		)
		(fp_line
			(start 0.67945 -0.305054)
			(end 0.12065 -0.305054)
			(stroke
				(width 0.1)
				(type default)
			)
			(layer "B.Fab")
		)
		(fp_line
			(start 0.12065 -0.305054)
			(end 0.12065 -0.2794)
			(stroke
				(width 0.1)
				(type default)
			)
			(layer "B.Fab")
		)
		(fp_line
			(start -0.12065 -0.3048)
			(end -0.67945 -0.3048)
			(stroke
				(width 0.1)
				(type default)
			)
			(layer "B.Fab")
		)
		(fp_line
			(start -0.67945 -0.3048)
			(end -0.67945 0.3048)
			(stroke
				(width 0.1)
				(type default)
			)
			(layer "B.Fab")
		)
		(fp_line
			(start 0.12065 -0.2794)
			(end -0.12065 -0.2794)
			(stroke
				(width 0.1)
				(type default)
			)
			(layer "B.Fab")
		)
		(fp_line
			(start -0.12065 -0.2794)
			(end -0.12065 -0.3048)
			(stroke
				(width 0.1)
				(type default)
			)
			(layer "B.Fab")
		)
		(fp_line
			(start 0.12065 0.2794)
			(end 0.12065 0.3048)
			(stroke
				(width 0.1)
				(type default)
			)
			(layer "B.Fab")
		)
		(fp_line
			(start -0.120396 0.2794)
			(end 0.12065 0.2794)
			(stroke
				(width 0.1)
				(type default)
			)
			(layer "B.Fab")
		)
		(fp_line
			(start 0.67945 0.3048)
			(end 0.67945 -0.305054)
			(stroke
				(width 0.1)
				(type default)
			)
			(layer "B.Fab")
		)
		(fp_line
			(start 0.12065 0.3048)
			(end 0.67945 0.3048)
			(stroke
				(width 0.1)
				(type default)
			)
			(layer "B.Fab")
		)
		(fp_line
			(start -0.120396 0.3048)
			(end -0.120396 0.2794)
			(stroke
				(width 0.1)
				(type default)
			)
			(layer "B.Fab")
		)
		(fp_line
			(start -0.67945 0.3048)
			(end -0.120396 0.3048)
			(stroke
				(width 0.1)
				(type default)
			)
			(layer "B.Fab")
		)
		(pad "1" smd circle
			(at 0.40005 0 270)
			(size 0 0)
			(layers "B.Cu" "B.Mask" "B.Paste")
			(net "P12V_HSC_ADC_P")
		)
		(pad "2" smd circle
			(at -0.40005 0 270)
			(size 0 0)
			(layers "B.Cu" "B.Mask" "B.Paste")
			(net "P12V_HSC_SENSE2_R1_P")
		)
	)
	(footprint ""
		(layer "B.Cu")
		(at 355.397308 -237.967266 -90)
		(property "Reference" "C395"
			(at 0 0 90)
			(layer "B.SilkS")
			(hide yes)
			(effects
				(font
					(size 1.27 1.27)
				)
				(justify mirror)
			)
		)
		(property "Value" ""
			(at 0 0 90)
			(layer "B.Fab")
			(effects
				(font
					(size 1.27 1.27)
				)
				(justify mirror)
			)
		)
		(duplicate_pad_numbers_are_jumpers no)
		(fp_line
			(start -1.524 0.762)
			(end 1.524 0.762)
			(stroke
				(width 0.1524)
				(type default)
			)
			(layer "B.SilkS")
		)
		(fp_line
			(start 1.524 0.762)
			(end 1.524 -0.762)
			(stroke
				(width 0.1524)
				(type default)
			)
			(layer "B.SilkS")
		)
		(fp_line
			(start -1.524 -0.762)
			(end -1.524 0.762)
			(stroke
				(width 0.1524)
				(type default)
			)
			(layer "B.SilkS")
		)
		(fp_line
			(start 1.524 -0.762)
			(end -1.524 -0.762)
			(stroke
				(width 0.1524)
				(type default)
			)
			(layer "B.SilkS")
		)
		(fp_line
			(start -1.1049 0.724916)
			(end -1.1049 -0.724916)
			(stroke
				(width 0.1)
				(type default)
			)
			(layer "B.Fab")
		)
		(fp_line
			(start 1.1049 0.724916)
			(end -1.1049 0.724916)
			(stroke
				(width 0.1)
				(type default)
			)
			(layer "B.Fab")
		)
		(fp_line
			(start -1.1049 -0.724916)
			(end 1.1049 -0.724916)
			(stroke
				(width 0.1)
				(type default)
			)
			(layer "B.Fab")
		)
		(fp_line
			(start 1.1049 -0.724916)
			(end 1.1049 0.724916)
			(stroke
				(width 0.1)
				(type default)
			)
			(layer "B.Fab")
		)
		(pad "1" smd rect
			(at 0.889 0 270)
			(size 1.016 1.27)
			(layers "B.Cu" "B.Mask" "B.Paste")
			(net "PVNN_MAIN_CPU0")
		)
		(pad "2" smd rect
			(at -0.889 0 270)
			(size 1.016 1.27)
			(layers "B.Cu" "B.Mask" "B.Paste")
			(net "GND")
		)
	)
	(footprint ""
		(layer "B.Cu")
		(at 320.886582 -66.955924 -90)
		(property "Reference" "C1243"
			(at 0 0 90)
			(layer "B.SilkS")
			(hide yes)
			(effects
				(font
					(size 1.27 1.27)
				)
				(justify mirror)
			)
		)
		(property "Value" ""
			(at 0 0 90)
			(layer "B.Fab")
			(effects
				(font
					(size 1.27 1.27)
				)
				(justify mirror)
			)
		)
		(duplicate_pad_numbers_are_jumpers no)
		(fp_line
			(start -1.524 0.762)
			(end 1.524 0.762)
			(stroke
				(width 0.1524)
				(type default)
			)
			(layer "B.SilkS")
		)
		(fp_line
			(start 1.524 0.762)
			(end 1.524 -0.762)
			(stroke
				(width 0.1524)
				(type default)
			)
			(layer "B.SilkS")
		)
		(fp_line
			(start -1.524 -0.762)
			(end -1.524 0.762)
			(stroke
				(width 0.1524)
				(type default)
			)
			(layer "B.SilkS")
		)
		(fp_line
			(start 1.524 -0.762)
			(end -1.524 -0.762)
			(stroke
				(width 0.1524)
				(type default)
			)
			(layer "B.SilkS")
		)
		(fp_line
			(start -1.1049 0.724916)
			(end -1.1049 -0.724916)
			(stroke
				(width 0.1)
				(type default)
			)
			(layer "B.Fab")
		)
		(fp_line
			(start 1.1049 0.724916)
			(end -1.1049 0.724916)
			(stroke
				(width 0.1)
				(type default)
			)
			(layer "B.Fab")
		)
		(fp_line
			(start -1.1049 -0.724916)
			(end 1.1049 -0.724916)
			(stroke
				(width 0.1)
				(type default)
			)
			(layer "B.Fab")
		)
		(fp_line
			(start 1.1049 -0.724916)
			(end 1.1049 0.724916)
			(stroke
				(width 0.1)
				(type default)
			)
			(layer "B.Fab")
		)
		(pad "1" smd rect
			(at 0.889 0 270)
			(size 1.016 1.27)
			(layers "B.Cu" "B.Mask" "B.Paste")
			(net "P3V3_AUX")
		)
		(pad "2" smd rect
			(at -0.889 0 270)
			(size 1.016 1.27)
			(layers "B.Cu" "B.Mask" "B.Paste")
			(net "GND")
		)
	)
)
